(kicad_pcb
	(version 20260206)
	(generator "pcbnew")
	(generator_version "10.0")
	(general
		(thickness 1.6)
		(legacy_teardrops no)
	)
	(paper "A4")
	(title_block
		(title "01162023_DA0F0TEBIF0_F0T_Expander_BD_F_brd_V02_OCP.brd")
		(comment 1 "Grand Teton / footprints 5966-5972 of 9728")
	)
	(layers
		(0 "F.Cu" signal "TOP")
		(4 "In1.Cu" signal "GND")
		(6 "In2.Cu" signal "VCC")
		(8 "In3.Cu" signal "VCC1")
		(10 "In4.Cu" signal "GND1")
		(12 "In5.Cu" signal "IN1")
		(14 "In6.Cu" signal "GND2")
		(16 "In7.Cu" signal "IN2")
		(18 "In8.Cu" signal "GND3")
		(20 "In9.Cu" signal "IN3")
		(22 "In10.Cu" signal "GND4")
		(24 "In11.Cu" signal "IN4")
		(26 "In12.Cu" signal "GND5")
		(28 "In13.Cu" signal "IN5")
		(30 "In14.Cu" signal "GND6")
		(32 "In15.Cu" signal "IN6")
		(34 "In16.Cu" signal "GND7")
		(2 "B.Cu" signal "BOTTOM")
		(9 "F.Adhes" user "F.Adhesive")
		(11 "B.Adhes" user "B.Adhesive")
		(13 "F.Paste" user "Package Geometry/Pastemask Top")
		(15 "B.Paste" user "Package Geometry/Pastemask Bottom")
		(5 "F.SilkS" user "Ref Des/Silkscreen Top")
		(7 "B.SilkS" user "Ref Des/Silkscreen Bottom")
		(1 "F.Mask" user "Board Geometry/Soldermask Top")
		(3 "B.Mask" user "Board Geometry/Soldermask Bottom")
		(17 "Dwgs.User" user "User.Drawings")
		(19 "Cmts.User" user "User.Comments")
		(21 "Eco1.User" user "User.Eco1")
		(23 "Eco2.User" user "User.Eco2")
		(25 "Edge.Cuts" user "Board Geometry/Outline")
		(27 "Margin" user)
		(31 "F.CrtYd" user "Package Geometry/Place Bound Top")
		(29 "B.CrtYd" user "Package Geometry/Place Bound Bottom")
		(35 "F.Fab" user "Ref Des/Assembly Top")
		(33 "B.Fab" user "Ref Des/Assembly Bottom")
	)
	(footprint ""
		(layer "F.Cu")
		(at 256.717546 -207.1116 -90)
		(property "Reference" "R5643"
			(at 0 0 270)
			(layer "F.SilkS")
			(hide yes)
			(effects
				(font
					(size 1.27 1.27)
				)
			)
		)
		(property "Value" ""
			(at 0 0 270)
			(layer "F.Fab")
			(effects
				(font
					(size 1.27 1.27)
				)
			)
		)
		(duplicate_pad_numbers_are_jumpers no)
		(fp_line
			(start -0.7874 0.4064)
			(end -0.7874 -0.4064)
			(stroke
				(width 0.1524)
				(type default)
			)
			(layer "F.SilkS")
		)
		(fp_line
			(start 0.7874 0.4064)
			(end -0.7874 0.4064)
			(stroke
				(width 0.1524)
				(type default)
			)
			(layer "F.SilkS")
		)
		(fp_line
			(start -0.7874 -0.4064)
			(end 0.7874 -0.4064)
			(stroke
				(width 0.1524)
				(type default)
			)
			(layer "F.SilkS")
		)
		(fp_line
			(start 0.7874 -0.4064)
			(end 0.7874 0.4064)
			(stroke
				(width 0.1524)
				(type default)
			)
			(layer "F.SilkS")
		)
		(fp_line
			(start -0.67945 0.3048)
			(end -0.67945 -0.305054)
			(stroke
				(width 0.1)
				(type default)
			)
			(layer "F.Fab")
		)
		(fp_line
			(start -0.12065 0.3048)
			(end -0.67945 0.3048)
			(stroke
				(width 0.1)
				(type default)
			)
			(layer "F.Fab")
		)
		(fp_line
			(start 0.120396 0.3048)
			(end 0.120396 0.2794)
			(stroke
				(width 0.1)
				(type default)
			)
			(layer "F.Fab")
		)
		(fp_line
			(start 0.67945 0.3048)
			(end 0.120396 0.3048)
			(stroke
				(width 0.1)
				(type default)
			)
			(layer "F.Fab")
		)
		(fp_line
			(start -0.12065 0.2794)
			(end -0.12065 0.3048)
			(stroke
				(width 0.1)
				(type default)
			)
			(layer "F.Fab")
		)
		(fp_line
			(start 0.120396 0.2794)
			(end -0.12065 0.2794)
			(stroke
				(width 0.1)
				(type default)
			)
			(layer "F.Fab")
		)
		(fp_line
			(start -0.12065 -0.2794)
			(end 0.12065 -0.2794)
			(stroke
				(width 0.1)
				(type default)
			)
			(layer "F.Fab")
		)
		(fp_line
			(start 0.12065 -0.2794)
			(end 0.12065 -0.3048)
			(stroke
				(width 0.1)
				(type default)
			)
			(layer "F.Fab")
		)
		(fp_line
			(start 0.12065 -0.3048)
			(end 0.67945 -0.3048)
			(stroke
				(width 0.1)
				(type default)
			)
			(layer "F.Fab")
		)
		(fp_line
			(start 0.67945 -0.3048)
			(end 0.67945 0.3048)
			(stroke
				(width 0.1)
				(type default)
			)
			(layer "F.Fab")
		)
		(fp_line
			(start -0.67945 -0.305054)
			(end -0.12065 -0.305054)
			(stroke
				(width 0.1)
				(type default)
			)
			(layer "F.Fab")
		)
		(fp_line
			(start -0.12065 -0.305054)
			(end -0.12065 -0.2794)
			(stroke
				(width 0.1)
				(type default)
			)
			(layer "F.Fab")
		)
		(pad "1" smd circle
			(at -0.40005 0 270)
			(size 0 0)
			(layers "F.Cu" "F.Mask" "F.Paste")
			(net "JTAG_BIC_TDI_R")
		)
		(pad "2" smd circle
			(at 0.40005 0 270)
			(size 0 0)
			(layers "F.Cu" "F.Mask" "F.Paste")
			(net "JTAG_BIC_TDI_R1")
		)
	)
	(footprint ""
		(layer "F.Cu")
		(at 262.281924 -299.391832 180)
		(property "Reference" "C3379"
			(at 0 0 180)
			(layer "F.SilkS")
			(hide yes)
			(effects
				(font
					(size 1.27 1.27)
				)
			)
		)
		(property "Value" ""
			(at 0 0 180)
			(layer "F.Fab")
			(effects
				(font
					(size 1.27 1.27)
				)
			)
		)
		(duplicate_pad_numbers_are_jumpers no)
		(fp_line
			(start 1.2954 0.5842)
			(end -1.2954 0.5842)
			(stroke
				(width 0.1524)
				(type default)
			)
			(layer "F.SilkS")
		)
		(fp_line
			(start 1.2954 -0.5842)
			(end 1.2954 0.5842)
			(stroke
				(width 0.1524)
				(type default)
			)
			(layer "F.SilkS")
		)
		(fp_line
			(start -1.2954 0.5842)
			(end -1.2954 -0.5842)
			(stroke
				(width 0.1524)
				(type default)
			)
			(layer "F.SilkS")
		)
		(fp_line
			(start -1.2954 -0.5842)
			(end 1.2954 -0.5842)
			(stroke
				(width 0.1524)
				(type default)
			)
			(layer "F.SilkS")
		)
		(fp_line
			(start 1.1938 0.4064)
			(end 0.8636 0.4064)
			(stroke
				(width 0.1)
				(type default)
			)
			(layer "F.Fab")
		)
		(fp_line
			(start 1.1938 -0.4064)
			(end 1.1938 0.4064)
			(stroke
				(width 0.1)
				(type default)
			)
			(layer "F.Fab")
		)
		(fp_line
			(start 0.8636 0.4572)
			(end -0.8636 0.4572)
			(stroke
				(width 0.1)
				(type default)
			)
			(layer "F.Fab")
		)
		(fp_line
			(start 0.8636 0.4064)
			(end 0.8636 0.4572)
			(stroke
				(width 0.1)
				(type default)
			)
			(layer "F.Fab")
		)
		(fp_line
			(start 0.8636 -0.4064)
			(end 1.1938 -0.4064)
			(stroke
				(width 0.1)
				(type default)
			)
			(layer "F.Fab")
		)
		(fp_line
			(start 0.8636 -0.4572)
			(end 0.8636 -0.4064)
			(stroke
				(width 0.1)
				(type default)
			)
			(layer "F.Fab")
		)
		(fp_line
			(start -0.8636 0.4572)
			(end -0.8636 0.4064)
			(stroke
				(width 0.1)
				(type default)
			)
			(layer "F.Fab")
		)
		(fp_line
			(start -0.8636 0.4064)
			(end -1.1938 0.4064)
			(stroke
				(width 0.1)
				(type default)
			)
			(layer "F.Fab")
		)
		(fp_line
			(start -0.8636 -0.4064)
			(end -0.8636 -0.4572)
			(stroke
				(width 0.1)
				(type default)
			)
			(layer "F.Fab")
		)
		(fp_line
			(start -0.8636 -0.4572)
			(end 0.8636 -0.4572)
			(stroke
				(width 0.1)
				(type default)
			)
			(layer "F.Fab")
		)
		(fp_line
			(start -1.1938 0.4064)
			(end -1.1938 -0.4064)
			(stroke
				(width 0.1)
				(type default)
			)
			(layer "F.Fab")
		)
		(fp_line
			(start -1.1938 -0.4064)
			(end -0.8636 -0.4064)
			(stroke
				(width 0.1)
				(type default)
			)
			(layer "F.Fab")
		)
		(pad "1" smd rect
			(at -0.7366 0 90)
			(size 0.7112 0.8128)
			(layers "F.Cu" "F.Mask" "F.Paste")
			(net "PCEPLL1_VDDA18_PEX2_R")
		)
		(pad "2" smd rect
			(at 0.7366 0 90)
			(size 0.7112 0.8128)
			(layers "F.Cu" "F.Mask" "F.Paste")
			(net "GND")
		)
	)
	(footprint ""
		(layer "F.Cu")
		(at 323.573648 -298.885102 -90)
		(property "Reference" "R4017"
			(at 0 0 270)
			(layer "F.SilkS")
			(hide yes)
			(effects
				(font
					(size 1.27 1.27)
				)
			)
		)
		(property "Value" ""
			(at 0 0 270)
			(layer "F.Fab")
			(effects
				(font
					(size 1.27 1.27)
				)
			)
		)
		(duplicate_pad_numbers_are_jumpers no)
		(fp_line
			(start -0.7874 0.4064)
			(end -0.7874 -0.4064)
			(stroke
				(width 0.1524)
				(type default)
			)
			(layer "F.SilkS")
		)
		(fp_line
			(start 0.7874 0.4064)
			(end -0.7874 0.4064)
			(stroke
				(width 0.1524)
				(type default)
			)
			(layer "F.SilkS")
		)
		(fp_line
			(start -0.7874 -0.4064)
			(end 0.7874 -0.4064)
			(stroke
				(width 0.1524)
				(type default)
			)
			(layer "F.SilkS")
		)
		(fp_line
			(start 0.7874 -0.4064)
			(end 0.7874 0.4064)
			(stroke
				(width 0.1524)
				(type default)
			)
			(layer "F.SilkS")
		)
		(fp_line
			(start -0.67945 0.3048)
			(end -0.67945 -0.305054)
			(stroke
				(width 0.1)
				(type default)
			)
			(layer "F.Fab")
		)
		(fp_line
			(start -0.12065 0.3048)
			(end -0.67945 0.3048)
			(stroke
				(width 0.1)
				(type default)
			)
			(layer "F.Fab")
		)
		(fp_line
			(start 0.120396 0.3048)
			(end 0.120396 0.2794)
			(stroke
				(width 0.1)
				(type default)
			)
			(layer "F.Fab")
		)
		(fp_line
			(start 0.67945 0.3048)
			(end 0.120396 0.3048)
			(stroke
				(width 0.1)
				(type default)
			)
			(layer "F.Fab")
		)
		(fp_line
			(start -0.12065 0.2794)
			(end -0.12065 0.3048)
			(stroke
				(width 0.1)
				(type default)
			)
			(layer "F.Fab")
		)
		(fp_line
			(start 0.120396 0.2794)
			(end -0.12065 0.2794)
			(stroke
				(width 0.1)
				(type default)
			)
			(layer "F.Fab")
		)
		(fp_line
			(start -0.12065 -0.2794)
			(end 0.12065 -0.2794)
			(stroke
				(width 0.1)
				(type default)
			)
			(layer "F.Fab")
		)
		(fp_line
			(start 0.12065 -0.2794)
			(end 0.12065 -0.3048)
			(stroke
				(width 0.1)
				(type default)
			)
			(layer "F.Fab")
		)
		(fp_line
			(start 0.12065 -0.3048)
			(end 0.67945 -0.3048)
			(stroke
				(width 0.1)
				(type default)
			)
			(layer "F.Fab")
		)
		(fp_line
			(start 0.67945 -0.3048)
			(end 0.67945 0.3048)
			(stroke
				(width 0.1)
				(type default)
			)
			(layer "F.Fab")
		)
		(fp_line
			(start -0.67945 -0.305054)
			(end -0.12065 -0.305054)
			(stroke
				(width 0.1)
				(type default)
			)
			(layer "F.Fab")
		)
		(fp_line
			(start -0.12065 -0.305054)
			(end -0.12065 -0.2794)
			(stroke
				(width 0.1)
				(type default)
			)
			(layer "F.Fab")
		)
		(pad "1" smd circle
			(at -0.40005 0 270)
			(size 0 0)
			(layers "F.Cu" "F.Mask" "F.Paste")
			(net "P1V8_PEX")
		)
		(pad "2" smd circle
			(at 0.40005 0 270)
			(size 0 0)
			(layers "F.Cu" "F.Mask" "F.Paste")
			(net "I2C_PEX2_HOST_R_SCL")
		)
	)
	(footprint ""
		(layer "F.Cu")
		(at 83.034124 -8.078724)
		(property "Reference" "R5811"
			(at 0 0 0)
			(layer "F.SilkS")
			(hide yes)
			(effects
				(font
					(size 1.27 1.27)
				)
			)
		)
		(property "Value" ""
			(at 0 0 0)
			(layer "F.Fab")
			(effects
				(font
					(size 1.27 1.27)
				)
			)
		)
		(duplicate_pad_numbers_are_jumpers no)
		(fp_line
			(start -0.7874 -0.4064)
			(end 0.7874 -0.4064)
			(stroke
				(width 0.1524)
				(type default)
			)
			(layer "F.SilkS")
		)
		(fp_line
			(start -0.7874 0.4064)
			(end -0.7874 -0.4064)
			(stroke
				(width 0.1524)
				(type default)
			)
			(layer "F.SilkS")
		)
		(fp_line
			(start 0.7874 -0.4064)
			(end 0.7874 0.4064)
			(stroke
				(width 0.1524)
				(type default)
			)
			(layer "F.SilkS")
		)
		(fp_line
			(start 0.7874 0.4064)
			(end -0.7874 0.4064)
			(stroke
				(width 0.1524)
				(type default)
			)
			(layer "F.SilkS")
		)
		(fp_line
			(start -0.67945 -0.305054)
			(end -0.12065 -0.305054)
			(stroke
				(width 0.1)
				(type default)
			)
			(layer "F.Fab")
		)
		(fp_line
			(start -0.67945 0.3048)
			(end -0.67945 -0.305054)
			(stroke
				(width 0.1)
				(type default)
			)
			(layer "F.Fab")
		)
		(fp_line
			(start -0.12065 -0.305054)
			(end -0.12065 -0.2794)
			(stroke
				(width 0.1)
				(type default)
			)
			(layer "F.Fab")
		)
		(fp_line
			(start -0.12065 -0.2794)
			(end 0.12065 -0.2794)
			(stroke
				(width 0.1)
				(type default)
			)
			(layer "F.Fab")
		)
		(fp_line
			(start -0.12065 0.2794)
			(end -0.12065 0.3048)
			(stroke
				(width 0.1)
				(type default)
			)
			(layer "F.Fab")
		)
		(fp_line
			(start -0.12065 0.3048)
			(end -0.67945 0.3048)
			(stroke
				(width 0.1)
				(type default)
			)
			(layer "F.Fab")
		)
		(fp_line
			(start 0.120396 0.2794)
			(end -0.12065 0.2794)
			(stroke
				(width 0.1)
				(type default)
			)
			(layer "F.Fab")
		)
		(fp_line
			(start 0.120396 0.3048)
			(end 0.120396 0.2794)
			(stroke
				(width 0.1)
				(type default)
			)
			(layer "F.Fab")
		)
		(fp_line
			(start 0.12065 -0.3048)
			(end 0.67945 -0.3048)
			(stroke
				(width 0.1)
				(type default)
			)
			(layer "F.Fab")
		)
		(fp_line
			(start 0.12065 -0.2794)
			(end 0.12065 -0.3048)
			(stroke
				(width 0.1)
				(type default)
			)
			(layer "F.Fab")
		)
		(fp_line
			(start 0.67945 -0.3048)
			(end 0.67945 0.3048)
			(stroke
				(width 0.1)
				(type default)
			)
			(layer "F.Fab")
		)
		(fp_line
			(start 0.67945 0.3048)
			(end 0.120396 0.3048)
			(stroke
				(width 0.1)
				(type default)
			)
			(layer "F.Fab")
		)
		(pad "1" smd circle
			(at -0.40005 0)
			(size 0 0)
			(layers "F.Cu" "F.Mask" "F.Paste")
			(net "LM75_2_A0")
		)
		(pad "2" smd circle
			(at 0.40005 0)
			(size 0 0)
			(layers "F.Cu" "F.Mask" "F.Paste")
			(net "GND")
		)
	)
	(footprint ""
		(layer "F.Cu")
		(at 365.506 -202.819 180)
		(property "Reference" "R4699"
			(at 0 0 180)
			(layer "F.SilkS")
			(hide yes)
			(effects
				(font
					(size 1.27 1.27)
				)
			)
		)
		(property "Value" ""
			(at 0 0 180)
			(layer "F.Fab")
			(effects
				(font
					(size 1.27 1.27)
				)
			)
		)
		(duplicate_pad_numbers_are_jumpers no)
		(fp_line
			(start 0.7874 0.4064)
			(end -0.7874 0.4064)
			(stroke
				(width 0.1524)
				(type default)
			)
			(layer "F.SilkS")
		)
		(fp_line
			(start 0.7874 -0.4064)
			(end 0.7874 0.4064)
			(stroke
				(width 0.1524)
				(type default)
			)
			(layer "F.SilkS")
		)
		(fp_line
			(start -0.7874 0.4064)
			(end -0.7874 -0.4064)
			(stroke
				(width 0.1524)
				(type default)
			)
			(layer "F.SilkS")
		)
		(fp_line
			(start -0.7874 -0.4064)
			(end 0.7874 -0.4064)
			(stroke
				(width 0.1524)
				(type default)
			)
			(layer "F.SilkS")
		)
		(fp_line
			(start 0.67945 0.3048)
			(end 0.120396 0.3048)
			(stroke
				(width 0.1)
				(type default)
			)
			(layer "F.Fab")
		)
		(fp_line
			(start 0.67945 -0.3048)
			(end 0.67945 0.3048)
			(stroke
				(width 0.1)
				(type default)
			)
			(layer "F.Fab")
		)
		(fp_line
			(start 0.12065 -0.2794)
			(end 0.12065 -0.3048)
			(stroke
				(width 0.1)
				(type default)
			)
			(layer "F.Fab")
		)
		(fp_line
			(start 0.12065 -0.3048)
			(end 0.67945 -0.3048)
			(stroke
				(width 0.1)
				(type default)
			)
			(layer "F.Fab")
		)
		(fp_line
			(start 0.120396 0.3048)
			(end 0.120396 0.2794)
			(stroke
				(width 0.1)
				(type default)
			)
			(layer "F.Fab")
		)
		(fp_line
			(start 0.120396 0.2794)
			(end -0.12065 0.2794)
			(stroke
				(width 0.1)
				(type default)
			)
			(layer "F.Fab")
		)
		(fp_line
			(start -0.12065 0.3048)
			(end -0.67945 0.3048)
			(stroke
				(width 0.1)
				(type default)
			)
			(layer "F.Fab")
		)
		(fp_line
			(start -0.12065 0.2794)
			(end -0.12065 0.3048)
			(stroke
				(width 0.1)
				(type default)
			)
			(layer "F.Fab")
		)
		(fp_line
			(start -0.12065 -0.2794)
			(end 0.12065 -0.2794)
			(stroke
				(width 0.1)
				(type default)
			)
			(layer "F.Fab")
		)
		(fp_line
			(start -0.12065 -0.305054)
			(end -0.12065 -0.2794)
			(stroke
				(width 0.1)
				(type default)
			)
			(layer "F.Fab")
		)
		(fp_line
			(start -0.67945 0.3048)
			(end -0.67945 -0.305054)
			(stroke
				(width 0.1)
				(type default)
			)
			(layer "F.Fab")
		)
		(fp_line
			(start -0.67945 -0.305054)
			(end -0.12065 -0.305054)
			(stroke
				(width 0.1)
				(type default)
			)
			(layer "F.Fab")
		)
		(pad "1" smd circle
			(at -0.40005 0 180)
			(size 0 0)
			(layers "F.Cu" "F.Mask" "F.Paste")
			(net "GND")
		)
		(pad "2" smd circle
			(at 0.40005 0 180)
			(size 0 0)
			(layers "F.Cu" "F.Mask" "F.Paste")
			(net "PCA9555_0_PEX1_A1")
		)
	)
	(footprint ""
		(layer "F.Cu")
		(at 28.633928 -343.952322 90)
		(property "Reference" "C183"
			(at 0 0 90)
			(layer "F.SilkS")
			(hide yes)
			(effects
				(font
					(size 1.27 1.27)
				)
			)
		)
		(property "Value" ""
			(at 0 0 90)
			(layer "F.Fab")
			(effects
				(font
					(size 1.27 1.27)
				)
			)
		)
		(duplicate_pad_numbers_are_jumpers no)
		(fp_line
			(start 0.299974 -0.150114)
			(end 0.299974 0.150114)
			(stroke
				(width 0.1)
				(type default)
			)
			(layer "F.Fab")
		)
		(fp_line
			(start -0.299974 -0.150114)
			(end 0.299974 -0.150114)
			(stroke
				(width 0.1)
				(type default)
			)
			(layer "F.Fab")
		)
		(fp_line
			(start 0.299974 0.150114)
			(end -0.299974 0.150114)
			(stroke
				(width 0.1)
				(type default)
			)
			(layer "F.Fab")
		)
		(fp_line
			(start -0.299974 0.150114)
			(end -0.299974 -0.150114)
			(stroke
				(width 0.1)
				(type default)
			)
			(layer "F.Fab")
		)
		(pad "1" smd rect
			(at -0.2667 0 90)
			(size 0.3048 0.381)
			(layers "F.Cu" "F.Mask" "F.Paste")
			(net "P5E_PEX0_STN7_TX_DP<116>")
		)
		(pad "2" smd rect
			(at 0.2667 0 90)
			(size 0.3048 0.381)
			(layers "F.Cu" "F.Mask" "F.Paste")
			(net "P5E_PEX0_STN7_TX_C_DP<116>")
		)
	)
	(footprint ""
		(layer "F.Cu")
		(at 263.654286 -252.356874 -90)
		(property "Reference" "R1360"
			(at 0 0 270)
			(layer "F.SilkS")
			(hide yes)
			(effects
				(font
					(size 1.27 1.27)
				)
			)
		)
		(property "Value" ""
			(at 0 0 270)
			(layer "F.Fab")
			(effects
				(font
					(size 1.27 1.27)
				)
			)
		)
		(duplicate_pad_numbers_are_jumpers no)
		(fp_line
			(start -0.7874 0.4064)
			(end -0.7874 -0.4064)
			(stroke
				(width 0.1524)
				(type default)
			)
			(layer "F.SilkS")
		)
		(fp_line
			(start 0.7874 0.4064)
			(end -0.7874 0.4064)
			(stroke
				(width 0.1524)
				(type default)
			)
			(layer "F.SilkS")
		)
		(fp_line
			(start -0.7874 -0.4064)
			(end 0.7874 -0.4064)
			(stroke
				(width 0.1524)
				(type default)
			)
			(layer "F.SilkS")
		)
		(fp_line
			(start 0.7874 -0.4064)
			(end 0.7874 0.4064)
			(stroke
				(width 0.1524)
				(type default)
			)
			(layer "F.SilkS")
		)
		(fp_line
			(start -0.67945 0.3048)
			(end -0.67945 -0.305054)
			(stroke
				(width 0.1)
				(type default)
			)
			(layer "F.Fab")
		)
		(fp_line
			(start -0.12065 0.3048)
			(end -0.67945 0.3048)
			(stroke
				(width 0.1)
				(type default)
			)
			(layer "F.Fab")
		)
		(fp_line
			(start 0.120396 0.3048)
			(end 0.120396 0.2794)
			(stroke
				(width 0.1)
				(type default)
			)
			(layer "F.Fab")
		)
		(fp_line
			(start 0.67945 0.3048)
			(end 0.120396 0.3048)
			(stroke
				(width 0.1)
				(type default)
			)
			(layer "F.Fab")
		)
		(fp_line
			(start -0.12065 0.2794)
			(end -0.12065 0.3048)
			(stroke
				(width 0.1)
				(type default)
			)
			(layer "F.Fab")
		)
		(fp_line
			(start 0.120396 0.2794)
			(end -0.12065 0.2794)
			(stroke
				(width 0.1)
				(type default)
			)
			(layer "F.Fab")
		)
		(fp_line
			(start -0.12065 -0.2794)
			(end 0.12065 -0.2794)
			(stroke
				(width 0.1)
				(type default)
			)
			(layer "F.Fab")
		)
		(fp_line
			(start 0.12065 -0.2794)
			(end 0.12065 -0.3048)
			(stroke
				(width 0.1)
				(type default)
			)
			(layer "F.Fab")
		)
		(fp_line
			(start 0.12065 -0.3048)
			(end 0.67945 -0.3048)
			(stroke
				(width 0.1)
				(type default)
			)
			(layer "F.Fab")
		)
		(fp_line
			(start 0.67945 -0.3048)
			(end 0.67945 0.3048)
			(stroke
				(width 0.1)
				(type default)
			)
			(layer "F.Fab")
		)
		(fp_line
			(start -0.67945 -0.305054)
			(end -0.12065 -0.305054)
			(stroke
				(width 0.1)
				(type default)
			)
			(layer "F.Fab")
		)
		(fp_line
			(start -0.12065 -0.305054)
			(end -0.12065 -0.2794)
			(stroke
				(width 0.1)
				(type default)
			)
			(layer "F.Fab")
		)
		(pad "1" smd circle
			(at -0.40005 0 270)
			(size 0 0)
			(layers "F.Cu" "F.Mask" "F.Paste")
			(net "GND")
		)
		(pad "2" smd circle
			(at 0.40005 0 270)
			(size 0 0)
			(layers "F.Cu" "F.Mask" "F.Paste")
			(net "PEX2_MODE_SEL4")
		)
	)
)
